# BASEBOARD_FAB2 (Tioga Pass) — schematic netlist excerpt (pin names and nets, part order shuffled) for the footprints in the layout excerpt that follows; sources: Cadence DE-HDL packaged netlist, KiCad conversion of Wiwynn_Tioga_Pass_MB.brd

C1E7  CAP  0.22UF 16V 10% X7R  pkg 0402  page 207 : A = P5V_STBY ; B = GND
C25W92  CAP  1.0UF 16V 10% X6S  pkg 0402  page 255 : A = P3V3_STBY ; B = GND
C6B12  CAP  0.22UF 16V 10% X7R  pkg 0402  page 105 : A = P3E_CPU0_PE1_PCH_TXP<12> ; B = P3E_CPU0_PE1_PCH_C_TXP<12>

(kicad_pcb
	(version 20260206)
	(generator "pcbnew")
	(generator_version "10.0")
	(general
		(thickness 1.6)
		(legacy_teardrops no)
	)
	(paper "A4")
	(title_block
		(title "Wiwynn_Tioga_Pass_MB.brd")
		(comment 1 "Tioga Pass / footprints 166-168 of 4770")
	)
	(layers
		(0 "F.Cu" signal "TOP")
		(4 "In1.Cu" signal "L2GND")
		(6 "In2.Cu" signal "L3")
		(8 "In3.Cu" signal "L4GND")
		(10 "In4.Cu" signal "L5")
		(12 "In5.Cu" signal "L6GND")
		(14 "In6.Cu" signal "L7VCC")
		(16 "In7.Cu" signal "L8VCC")
		(18 "In8.Cu" signal "L9GND")
		(20 "In9.Cu" signal "L10")
		(22 "In10.Cu" signal "L11GND")
		(24 "In11.Cu" signal "L12")
		(26 "In12.Cu" signal "L13GND")
		(2 "B.Cu" signal "BOTTOM")
		(9 "F.Adhes" user "F.Adhesive")
		(11 "B.Adhes" user "B.Adhesive")
		(13 "F.Paste" user "Package Geometry/Pastemask Top")
		(15 "B.Paste" user "Package Geometry/Pastemask Bottom")
		(5 "F.SilkS" user "Ref Des/Silkscreen Top")
		(7 "B.SilkS" user "Ref Des/Silkscreen Bottom")
		(1 "F.Mask" user "Board Geometry/Soldermask Top")
		(3 "B.Mask" user "Board Geometry/Soldermask Bottom")
		(17 "Dwgs.User" user "User.Drawings")
		(19 "Cmts.User" user "User.Comments")
		(21 "Eco1.User" user "User.Eco1")
		(23 "Eco2.User" user "User.Eco2")
		(25 "Edge.Cuts" user "Board Geometry/Outline")
		(27 "Margin" user)
		(31 "F.CrtYd" user "Package Geometry/Place Bound Top")
		(29 "B.CrtYd" user "Package Geometry/Place Bound Bottom")
		(35 "F.Fab" user "Ref Des/Assembly Top")
		(33 "B.Fab" user "Ref Des/Assembly Bottom")
	)
	(footprint ""
		(layer "F.Cu")
		(at 321.16522 -119.26316 90)
		(property "Reference" "C6B12"
			(at -0.8382 -0.67818 90)
			(unlocked yes)
			(layer "F.SilkS")
			(effects
				(font
					(size 0.4064 0.254)
					(thickness 0.1524)
				)
				(justify left)
			)
		)
		(property "Value" ""
			(at 0 0 90)
			(layer "F.Fab")
			(effects
				(font
					(size 1.27 1.27)
				)
			)
		)
		(duplicate_pad_numbers_are_jumpers no)
		(fp_poly
			(pts
				(xy 0.3048 -0.1016) (xy 0.3048 0.9906) (xy -0.3048 0.9906) (xy -0.3048 -0.1016)
			)
			(stroke
				(width 0)
				(type default)
			)
			(fill no)
			(layer "F.CrtYd")
		)
		(fp_line
			(start 0.3048 -0.1016)
			(end -0.3048 -0.1016)
			(stroke
				(width 0.1)
				(type default)
			)
			(layer "F.Fab")
		)
		(fp_line
			(start -0.3048 -0.1016)
			(end -0.3048 0.9906)
			(stroke
				(width 0.1)
				(type default)
			)
			(layer "F.Fab")
		)
		(fp_line
			(start 0.3048 0.9906)
			(end 0.3048 -0.1016)
			(stroke
				(width 0.1)
				(type default)
			)
			(layer "F.Fab")
		)
		(fp_line
			(start -0.3048 0.9906)
			(end 0.3048 0.9906)
			(stroke
				(width 0.1)
				(type default)
			)
			(layer "F.Fab")
		)
		(pad "1" smd rect
			(at 0 0 90)
			(size 0.508 0.508)
			(layers "F.Cu" "F.Mask" "F.Paste")
			(net "P3E_CPU0_PE1_PCH_TXP<12>")
		)
		(pad "2" smd rect
			(at 0 0.889 90)
			(size 0.508 0.508)
			(layers "F.Cu" "F.Mask" "F.Paste")
			(net "P3E_CPU0_PE1_PCH_C_TXP<12>")
		)
		(zone
			(layer "F.Cu")
			(hatch none 0.5)
			(connect_pads
				(clearance 0)
			)
			(min_thickness 0.25)
			(keepout
				(tracks allowed)
				(vias not_allowed)
				(pads allowed)
				(copperpour not_allowed)
				(footprints allowed)
			)
			(placement
				(enabled no)
				(sheetname "")
			)
			(fill
				(thermal_gap 0.5)
				(thermal_bridge_width 0.5)
				(island_removal_mode 0)
			)
			(polygon
				(pts
					(xy 321.41922 -119.00916) (xy 321.41922 -119.51716) (xy 321.80022 -119.51716) (xy 321.80022 -119.00916)
				)
			)
		)
		(zone
			(layer "F.Cu")
			(hatch none 0.5)
			(connect_pads
				(clearance 0)
			)
			(min_thickness 0.25)
			(keepout
				(tracks not_allowed)
				(vias allowed)
				(pads allowed)
				(copperpour not_allowed)
				(footprints allowed)
			)
			(placement
				(enabled no)
				(sheetname "")
			)
			(fill
				(thermal_gap 0.5)
				(thermal_bridge_width 0.5)
				(island_removal_mode 0)
			)
			(polygon
				(pts
					(xy 321.80022 -119.00916) (xy 321.80022 -119.51716) (xy 321.41922 -119.51716) (xy 321.41922 -119.00916)
				)
			)
		)
	)
	(footprint ""
		(layer "F.Cu")
		(at 33.178496 -53.221382 90)
		(property "Reference" "C1E7"
			(at 0 0 90)
			(layer "F.SilkS")
			(hide yes)
			(effects
				(font
					(size 1.27 1.27)
				)
			)
		)
		(property "Value" ""
			(at 0 0 90)
			(layer "F.Fab")
			(effects
				(font
					(size 1.27 1.27)
				)
			)
		)
		(duplicate_pad_numbers_are_jumpers no)
		(fp_rect
			(start 0.3048 0.9906)
			(end -0.3048 -0.1016)
			(stroke
				(width 0)
				(type default)
			)
			(fill no)
			(layer "F.CrtYd")
		)
		(fp_line
			(start 0.3048 -0.1016)
			(end -0.3048 -0.1016)
			(stroke
				(width 0.1)
				(type default)
			)
			(layer "F.Fab")
		)
		(fp_line
			(start -0.3048 -0.1016)
			(end -0.3048 0.9906)
			(stroke
				(width 0.1)
				(type default)
			)
			(layer "F.Fab")
		)
		(fp_line
			(start 0.3048 0.9906)
			(end 0.3048 -0.1016)
			(stroke
				(width 0.1)
				(type default)
			)
			(layer "F.Fab")
		)
		(fp_line
			(start -0.3048 0.9906)
			(end 0.3048 0.9906)
			(stroke
				(width 0.1)
				(type default)
			)
			(layer "F.Fab")
		)
		(pad "1" smd rect
			(at 0 0 90)
			(size 0.508 0.508)
			(layers "F.Cu" "F.Mask" "F.Paste")
			(net "P5V_STBY")
		)
		(pad "2" smd rect
			(at 0 0.889 90)
			(size 0.508 0.508)
			(layers "F.Cu" "F.Mask" "F.Paste")
			(net "GND")
		)
		(zone
			(layer "F.Cu")
			(hatch none 0.5)
			(connect_pads
				(clearance 0)
			)
			(min_thickness 0.25)
			(keepout
				(tracks allowed)
				(vias not_allowed)
				(pads allowed)
				(copperpour not_allowed)
				(footprints allowed)
			)
			(placement
				(enabled no)
				(sheetname "")
			)
			(fill
				(thermal_gap 0.5)
				(thermal_bridge_width 0.5)
				(island_removal_mode 0)
			)
			(polygon
				(pts
					(xy 33.813496 -53.475382) (xy 33.432496 -53.475382) (xy 33.432496 -52.967382) (xy 33.813496 -52.967382)
				)
			)
		)
		(zone
			(layer "F.Cu")
			(hatch none 0.5)
			(connect_pads
				(clearance 0)
			)
			(min_thickness 0.25)
			(keepout
				(tracks not_allowed)
				(vias allowed)
				(pads allowed)
				(copperpour not_allowed)
				(footprints allowed)
			)
			(placement
				(enabled no)
				(sheetname "")
			)
			(fill
				(thermal_gap 0.5)
				(thermal_bridge_width 0.5)
				(island_removal_mode 0)
			)
			(polygon
				(pts
					(xy 33.813496 -53.475382) (xy 33.432496 -53.475382) (xy 33.432496 -52.967382) (xy 33.813496 -52.967382)
				)
			)
		)
	)
	(footprint ""
		(layer "F.Cu")
		(at 444.1825 -146.5834 -90)
		(property "Reference" "C25W92"
			(at -0.8382 -0.67818 270)
			(unlocked yes)
			(layer "F.SilkS")
			(effects
				(font
					(size 0.4064 0.254)
					(thickness 0.1524)
				)
				(justify left)
			)
		)
		(property "Value" ""
			(at 0 0 270)
			(layer "F.Fab")
			(effects
				(font
					(size 1.27 1.27)
				)
			)
		)
		(duplicate_pad_numbers_are_jumpers no)
		(fp_poly
			(pts
				(xy 0.3048 -0.1016) (xy 0.3048 0.9906) (xy -0.3048 0.9906) (xy -0.3048 -0.1016)
			)
			(stroke
				(width 0)
				(type default)
			)
			(fill no)
			(layer "F.CrtYd")
		)
		(fp_line
			(start -0.3048 0.9906)
			(end 0.3048 0.9906)
			(stroke
				(width 0.1)
				(type default)
			)
			(layer "F.Fab")
		)
		(fp_line
			(start 0.3048 0.9906)
			(end 0.3048 -0.1016)
			(stroke
				(width 0.1)
				(type default)
			)
			(layer "F.Fab")
		)
		(fp_line
			(start -0.3048 -0.1016)
			(end -0.3048 0.9906)
			(stroke
				(width 0.1)
				(type default)
			)
			(layer "F.Fab")
		)
		(fp_line
			(start 0.3048 -0.1016)
			(end -0.3048 -0.1016)
			(stroke
				(width 0.1)
				(type default)
			)
			(layer "F.Fab")
		)
		(pad "1" smd rect
			(at 0 0 270)
			(size 0.508 0.508)
			(layers "F.Cu" "F.Mask" "F.Paste")
			(net "P3V3_STBY")
		)
		(pad "2" smd rect
			(at 0 0.889 270)
			(size 0.508 0.508)
			(layers "F.Cu" "F.Mask" "F.Paste")
			(net "GND")
		)
		(zone
			(layer "F.Cu")
			(hatch none 0.5)
			(connect_pads
				(clearance 0)
			)
			(min_thickness 0.25)
			(keepout
				(tracks not_allowed)
				(vias allowed)
				(pads allowed)
				(copperpour not_allowed)
				(footprints allowed)
			)
			(placement
				(enabled no)
				(sheetname "")
			)
			(fill
				(thermal_gap 0.5)
				(thermal_bridge_width 0.5)
				(island_removal_mode 0)
			)
			(polygon
				(pts
					(xy 443.5475 -146.8374) (xy 443.5475 -146.3294) (xy 443.9285 -146.3294) (xy 443.9285 -146.8374)
				)
			)
		)
		(zone
			(layer "F.Cu")
			(hatch none 0.5)
			(connect_pads
				(clearance 0)
			)
			(min_thickness 0.25)
			(keepout
				(tracks allowed)
				(vias not_allowed)
				(pads allowed)
				(copperpour not_allowed)
				(footprints allowed)
			)
			(placement
				(enabled no)
				(sheetname "")
			)
			(fill
				(thermal_gap 0.5)
				(thermal_bridge_width 0.5)
				(island_removal_mode 0)
			)
			(polygon
				(pts
					(xy 443.9285 -146.8374) (xy 443.9285 -146.3294) (xy 443.5475 -146.3294) (xy 443.5475 -146.8374)
				)
			)
		)
	)
)
